# BASEBOARD_FAB2 (Tioga Pass) — schematic netlist excerpt (pin names and nets, part order shuffled) for the footprints in the layout excerpt that follows; sources: Cadence DE-HDL packaged netlist, KiCad conversion of Wiwynn_Tioga_Pass_MB.brd

J6L1  SCONN288_H44441003  SCONN  pkg PIP  page 54
  \12v\(1)  = P12V_NVDIMM_DEF
  VSS(93)  = GND
  DQ(4)  = M_F_DQ<4>
  VSS(92)  = GND
  DQ(0)  = M_F_DQ<0>
  VSS(91)  = GND
  DQS9P  = M_F_DQS_DP<9>
  DQS9N  = M_F_DQS_DN<9>
  VSS(90)  = GND
  DQ(6)  = M_F_DQ<6>
  VSS(89)  = GND
  DQ(2)  = M_F_DQ<2>
  VSS(88)  = GND
  DQ(12)  = M_F_DQ<12>
  VSS(87)  = GND
  DQ(8)  = M_F_DQ<8>
  VSS(86)  = GND
  DQS10P  = M_F_DQS_DP<10>
  DQS10N  = M_F_DQS_DN<10>
  VSS(85)  = GND
  DQ(14)  = M_F_DQ<14>
  VSS(84)  = GND
  DQ(10)  = M_F_DQ<10>
  VSS(83)  = GND
  DQ(20)  = M_F_DQ<20>
  VSS(82)  = GND
  DQ(16)  = M_F_DQ<16>
  VSS(81)  = GND
  DQS11P  = M_F_DQS_DP<11>
  DQS11N  = M_F_DQS_DN<11>
  VSS(80)  = GND
  DQ(22)  = M_F_DQ<22>
  VSS(79)  = GND
  DQ(18)  = M_F_DQ<18>
  VSS(78)  = GND
  DQ(28)  = M_F_DQ<28>
  VSS(77)  = GND
  DQ(24)  = M_F_DQ<24>
  VSS(76)  = GND
  DQS12P  = M_F_DQS_DP<12>
  DQS12N  = M_F_DQS_DN<12>
  VSS(75)  = GND
  DQ(30)  = M_F_DQ<30>
  VSS(74)  = GND
  DQ(26)  = M_F_DQ<26>
  VSS(73)  = GND
  CB(4)  = M_F_ECC<4>
  VSS(72)  = GND
  CB(0)  = M_F_ECC<0>
  VSS(71)  = GND
  DQS17P  = M_F_DQS_DP<17>
  DQS17N  = M_F_DQS_DN<17>
  VSS(70)  = GND
  CB(6)  = M_F_ECC<6>
  VSS(69)  = GND
  CB(2)  = M_F_ECC<2>
  VSS(68)  = GND
  RESET_N  = M_DEF_RST_N
  VDD(25)  = PVDDQ_DEF
  CKE(0)  = M_F_CKE<2>
  VDD(24)  = PVDDQ_DEF
  ACT_N  = M_F_ACT_N
  BG(0)  = M_F_BG<0>
  VDD(23)  = PVDDQ_DEF
  A12  = M_F_MA<12>
  A9  = M_F_MA<9>
  VDD(22)  = PVDDQ_DEF
  A8  = M_F_MA<8>
  A6  = M_F_MA<6>
  VDD(21)  = PVDDQ_DEF
  A3  = M_F_MA<3>
  A1  = M_F_MA<1>
  VDD(20)  = PVDDQ_DEF
  CK0P  = M_F_CLK_DP<2>
  CK0N  = M_F_CLK_DN<2>
  VDD(19)  = PVDDQ_DEF
  VTT(1)  = PVTT_DEF
  EVENT_N  = FM_DIMM_EVENT_COD_N
  A0  = M_F_MA<0>
  VDD(18)  = PVDDQ_DEF
  BA(0)  = M_F_BA<0>
  A16_RAS_N  = M_F_MA<16>
  VDD(17)  = PVDDQ_DEF
  S0_N  = M_F_CS_N<4>
  VDD(16)  = PVDDQ_DEF
  A15_CAS_N  = M_F_MA<15>
  ODT(0)  = M_F_ODT<2>
  VDD(15)  = PVDDQ_DEF
  S1_N  = M_F_CS_N<5>
  VDD(14)  = PVDDQ_DEF
  ODT(1)  = M_F_ODT<3>
  VDD(13)  = PVDDQ_DEF
  S2_N_C(0)  = M_F_CS_N<6>
  VSS(67)  = GND
  DQ(36)  = M_F_DQ<36>
  VSS(66)  = GND
  DQ(32)  = M_F_DQ<32>
  VSS(65)  = GND
  DQS13P  = M_F_DQS_DP<13>
  DQS13N  = M_F_DQS_DN<13>
  VSS(64)  = GND
  DQ(38)  = M_F_DQ<38>
  VSS(63)  = GND
  DQ(34)  = M_F_DQ<34>
  VSS(62)  = GND
  DQ(44)  = M_F_DQ<44>
  VSS(61)  = GND
  DQ(40)  = M_F_DQ<40>
  VSS(60)  = GND
  DQS14P  = M_F_DQS_DP<14>
  DQS14N  = M_F_DQS_DN<14>
  VSS(59)  = GND
  DQ(46)  = M_F_DQ<46>
  VSS(58)  = GND
  DQ(42)  = M_F_DQ<42>
  VSS(57)  = GND
  DQ(52)  = M_F_DQ<52>
  VSS(56)  = GND
  DQ(48)  = M_F_DQ<48>
  VSS(55)  = GND
  DQS15P  = M_F_DQS_DP<15>
  DQS15N  = M_F_DQS_DN<15>
  VSS(54)  = GND
  DQ(54)  = M_F_DQ<54>
  VSS(53)  = GND
  DQ(50)  = M_F_DQ<50>
  VSS(52)  = GND
  DQ(60)  = M_F_DQ<60>
  VSS(51)  = GND
  DQ(56)  = M_F_DQ<56>
  VSS(50)  = GND
  DQS16P  = M_F_DQS_DP<16>
  DQS16N  = M_F_DQS_DN<16>
  VSS(49)  = GND
  DQ(62)  = M_F_DQ<62>
  VSS(48)  = GND
  DQ(58)  = M_F_DQ<58>
  VSS(47)  = GND
  SA(0)  = PVPP_DEF
  SA(1)  = GND
  SCL  = SMB_DDR_DEF_VPP_SCL
  VPP(4)  = PVPP_DEF
  VPP(3)  = PVPP_DEF
  RFU(2)  = TP_CH_F_DIMM_F1_RFU_2
  \12v\(0)  = P12V_NVDIMM_DEF
  VREFCA  = M_F_VREF
  VSS(46)  = GND
  DQ(5)  = M_F_DQ<5>
  VSS(45)  = GND
  DQ(1)  = M_F_DQ<1>
  VSS(44)  = GND
  DQS0N  = M_F_DQS_DN<0>
  DQS0P  = M_F_DQS_DP<0>
  VSS(43)  = GND
  DQ(7)  = M_F_DQ<7>
  VSS(42)  = GND
  DQ(3)  = M_F_DQ<3>
  VSS(41)  = GND
  DQ(13)  = M_F_DQ<13>
  VSS(40)  = GND
  DQ(9)  = M_F_DQ<9>
  VSS(39)  = GND
  DQS1N  = M_F_DQS_DN<1>
  DQS1P  = M_F_DQS_DP<1>
  VSS(38)  = GND
  DQ(15)  = M_F_DQ<15>
  VSS(37)  = GND
  DQ(11)  = M_F_DQ<11>
  VSS(36)  = GND
  DQ(21)  = M_F_DQ<21>
  VSS(35)  = GND
  DQ(17)  = M_F_DQ<17>
  VSS(34)  = GND
  DQS2N  = M_F_DQS_DN<2>
  DQS2P  = M_F_DQS_DP<2>
  VSS(33)  = GND
  DQ(23)  = M_F_DQ<23>
  VSS(32)  = GND
  DQ(19)  = M_F_DQ<19>
  VSS(31)  = GND
  DQ(29)  = M_F_DQ<29>
  VSS(30)  = GND
  DQ(25)  = M_F_DQ<25>
  VSS(29)  = GND
  DQS3N  = M_F_DQS_DN<3>
  DQS3P  = M_F_DQS_DP<3>
  VSS(28)  = GND
  DQ(31)  = M_F_DQ<31>
  VSS(27)  = GND
  DQ(27)  = M_F_DQ<27>
  VSS(26)  = GND
  CB(5)  = M_F_ECC<5>
  VSS(25)  = GND
  CB(1)  = M_F_ECC<1>
  VSS(24)  = GND
  DQS8N  = M_F_DQS_DN<8>
  DQS8P  = M_F_DQS_DP<8>
  VSS(23)  = GND
  CB(7)  = M_F_ECC<7>
  VSS(22)  = GND
  CB(3)  = M_F_ECC<3>
  VSS(21)  = GND
  CKE(1)  = M_F_CKE<3>
  VDD(12)  = PVDDQ_DEF
  RFU(0)  = TP_CH_F_DIMM_F1_RFU_0
  VDD(11)  = PVDDQ_DEF
  BG(1)  = M_F_BG<1>
  ALERT_N  = M_F_ALERT_N
  VDD(10)  = PVDDQ_DEF
  A11  = M_F_MA<11>
  A7  = M_F_MA<7>
  VDD(9)  = PVDDQ_DEF
  A5  = M_F_MA<5>
  A4  = M_F_MA<4>
  VDD(8)  = PVDDQ_DEF
  A2  = M_F_MA<2>
  VDD(7)  = PVDDQ_DEF
  CK1P  = M_F_CLK_DP<3>
  CK1N  = M_F_CLK_DN<3>
  VDD(6)  = PVDDQ_DEF
  VTT(0)  = PVTT_DEF
  PAR  = M_F_PAR
  VDD(5)  = PVDDQ_DEF
  BA(1)  = M_F_BA<1>
  A10  = M_F_MA<10>
  VDD(4)  = PVDDQ_DEF
  RFU(1)  = TP_CH_F_DIMM_F1_RFU_1
  A14_WE_N  = M_F_MA<14>
  VDD(3)  = PVDDQ_DEF
  SAVE_N_NC  = FM_ADR_COMPLETE_DEF_N
  VDD(2)  = PVDDQ_DEF
  A13  = M_F_MA<13>
  VDD(1)  = PVDDQ_DEF
  A17  = M_F_MA<17>
  C(2)  = M_F_C<2>
  VDD(0)  = PVDDQ_DEF
  S3_N_C(1)  = M_F_CS_N<7>
  SA(2)  = PVPP_DEF
  VSS(20)  = GND
  DQ(37)  = M_F_DQ<37>
  VSS(19)  = GND
  DQ(33)  = M_F_DQ<33>
  VSS(18)  = GND
  DQS4N  = M_F_DQS_DN<4>
  DQS4P  = M_F_DQS_DP<4>
  VSS(17)  = GND
  DQ(39)  = M_F_DQ<39>
  VSS(16)  = GND
  DQ(35)  = M_F_DQ<35>
  VSS(15)  = GND
  DQ(45)  = M_F_DQ<45>
  VSS(14)  = GND
  DQ(41)  = M_F_DQ<41>
  VSS(13)  = GND
  DQS5N  = M_F_DQS_DN<5>
  DQS5P  = M_F_DQS_DP<5>
  VSS(12)  = GND
  DQ(47)  = M_F_DQ<47>
  VSS(11)  = GND
  DQ(43)  = M_F_DQ<43>
  VSS(10)  = GND
  DQ(53)  = M_F_DQ<53>
  VSS(9)  = GND
  DQ(49)  = M_F_DQ<49>
  VSS(8)  = GND
  DQS6N  = M_F_DQS_DN<6>
  DQS6P  = M_F_DQS_DP<6>
  VSS(7)  = GND
  DQ(55)  = M_F_DQ<55>
  VSS(6)  = GND
  DQ(51)  = M_F_DQ<51>
  VSS(5)  = GND
  DQ(61)  = M_F_DQ<61>
  VSS(4)  = GND
  DQ(57)  = M_F_DQ<57>
  VSS(3)  = GND
  DQS7N  = M_F_DQS_DN<7>
  DQS7P  = M_F_DQS_DP<7>
  VSS(2)  = GND
  DQ(63)  = M_F_DQ<63>
  VSS(1)  = GND
  DQ(59)  = M_F_DQ<59>
  VSS(0)  = GND
  VDDSPD  = PVPP_DEF
  SDA  = SMB_DDR_DEF_VPP_SDA
  VPP(1)  = PVPP_DEF
  VPP(0)  = PVPP_DEF
  VPP(2)  = PVPP_DEF

(kicad_pcb
	(version 20260206)
	(generator "pcbnew")
	(generator_version "10.0")
	(general
		(thickness 1.6)
		(legacy_teardrops no)
	)
	(paper "A4")
	(title_block
		(title "Wiwynn_Tioga_Pass_MB.brd")
		(comment 1 "Tioga Pass / footprint 4129 of 4770 (J6L1), pads 152-201 of 291")
	)
	(layers
		(0 "F.Cu" signal "TOP")
		(4 "In1.Cu" signal "L2GND")
		(6 "In2.Cu" signal "L3")
		(8 "In3.Cu" signal "L4GND")
		(10 "In4.Cu" signal "L5")
		(12 "In5.Cu" signal "L6GND")
		(14 "In6.Cu" signal "L7VCC")
		(16 "In7.Cu" signal "L8VCC")
		(18 "In8.Cu" signal "L9GND")
		(20 "In9.Cu" signal "L10")
		(22 "In10.Cu" signal "L11GND")
		(24 "In11.Cu" signal "L12")
		(26 "In12.Cu" signal "L13GND")
		(2 "B.Cu" signal "BOTTOM")
		(9 "F.Adhes" user "F.Adhesive")
		(11 "B.Adhes" user "B.Adhesive")
		(13 "F.Paste" user "Package Geometry/Pastemask Top")
		(15 "B.Paste" user "Package Geometry/Pastemask Bottom")
		(5 "F.SilkS" user "Ref Des/Silkscreen Top")
		(7 "B.SilkS" user "Ref Des/Silkscreen Bottom")
		(1 "F.Mask" user "Board Geometry/Soldermask Top")
		(3 "B.Mask" user "Board Geometry/Soldermask Bottom")
		(17 "Dwgs.User" user "User.Drawings")
		(19 "Cmts.User" user "User.Comments")
		(21 "Eco1.User" user "User.Eco1")
		(23 "Eco2.User" user "User.Eco2")
		(25 "Edge.Cuts" user "Board Geometry/Outline")
		(27 "Margin" user)
		(31 "F.CrtYd" user "Package Geometry/Place Bound Top")
		(29 "B.CrtYd" user "Package Geometry/Place Bound Bottom")
		(35 "F.Fab" user "Ref Des/Assembly Top")
		(33 "B.Fab" user "Ref Des/Assembly Bottom")
	)
	(footprint ""
		(layer "B.Cu")
		(at 194.700398 -152.078436 90)
		(property "Reference" "J6L1"
			(at 2.200148 37.96411 0)
			(unlocked yes)
			(layer "B.SilkS")
			(effects
				(font
					(size 0.7874 0.5842)
					(thickness 0.1524)
				)
				(justify left mirror)
			)
		)
		(property "Value" ""
			(at 0 0 90)
			(layer "B.Fab")
			(effects
				(font
					(size 1.27 1.27)
				)
				(justify mirror)
			)
		)
		(duplicate_pad_numbers_are_jumpers no)
		(pad "149" smd rect
			(at -4.59994 3.400044 270)
			(size 1.8034 0.508)
			(layers "B.Cu" "B.Mask" "B.Paste")
			(net "GND")
		)
		(pad "150" smd rect
			(at -4.59994 4.249928 270)
			(size 1.8034 0.508)
			(layers "B.Cu" "B.Mask" "B.Paste")
			(net "M_F_DQ<1>")
		)
		(pad "151" smd rect
			(at -4.59994 5.100066 270)
			(size 1.8034 0.508)
			(layers "B.Cu" "B.Mask" "B.Paste")
			(net "GND")
		)
		(pad "152" smd rect
			(at -4.59994 5.94995 270)
			(size 1.8034 0.508)
			(layers "B.Cu" "B.Mask" "B.Paste")
			(net "M_F_DQS_DN<0>")
		)
		(pad "153" smd rect
			(at -4.59994 6.800088 270)
			(size 1.8034 0.508)
			(layers "B.Cu" "B.Mask" "B.Paste")
			(net "M_F_DQS_DP<0>")
		)
		(pad "154" smd rect
			(at -4.59994 7.649972 270)
			(size 1.8034 0.508)
			(layers "B.Cu" "B.Mask" "B.Paste")
			(net "GND")
		)
		(pad "155" smd rect
			(at -4.59994 8.50011 270)
			(size 1.8034 0.508)
			(layers "B.Cu" "B.Mask" "B.Paste")
			(net "M_F_DQ<7>")
		)
		(pad "156" smd rect
			(at -4.59994 9.349994 270)
			(size 1.8034 0.508)
			(layers "B.Cu" "B.Mask" "B.Paste")
			(net "GND")
		)
		(pad "157" smd rect
			(at -4.59994 10.199878 270)
			(size 1.8034 0.508)
			(layers "B.Cu" "B.Mask" "B.Paste")
			(net "M_F_DQ<3>")
		)
		(pad "158" smd rect
			(at -4.59994 11.050016 270)
			(size 1.8034 0.508)
			(layers "B.Cu" "B.Mask" "B.Paste")
			(net "GND")
		)
		(pad "159" smd rect
			(at -4.59994 11.8999 270)
			(size 1.8034 0.508)
			(layers "B.Cu" "B.Mask" "B.Paste")
			(net "M_F_DQ<13>")
		)
		(pad "160" smd rect
			(at -4.59994 12.750038 270)
			(size 1.8034 0.508)
			(layers "B.Cu" "B.Mask" "B.Paste")
			(net "GND")
		)
		(pad "161" smd rect
			(at -4.59994 13.599922 270)
			(size 1.8034 0.508)
			(layers "B.Cu" "B.Mask" "B.Paste")
			(net "M_F_DQ<9>")
		)
		(pad "162" smd rect
			(at -4.59994 14.45006 270)
			(size 1.8034 0.508)
			(layers "B.Cu" "B.Mask" "B.Paste")
			(net "GND")
		)
		(pad "163" smd rect
			(at -4.59994 15.299944 270)
			(size 1.8034 0.508)
			(layers "B.Cu" "B.Mask" "B.Paste")
			(net "M_F_DQS_DN<1>")
		)
		(pad "164" smd rect
			(at -4.59994 16.150082 270)
			(size 1.8034 0.508)
			(layers "B.Cu" "B.Mask" "B.Paste")
			(net "M_F_DQS_DP<1>")
		)
		(pad "165" smd rect
			(at -4.59994 16.999966 270)
			(size 1.8034 0.508)
			(layers "B.Cu" "B.Mask" "B.Paste")
			(net "GND")
		)
		(pad "166" smd rect
			(at -4.59994 17.850104 270)
			(size 1.8034 0.508)
			(layers "B.Cu" "B.Mask" "B.Paste")
			(net "M_F_DQ<15>")
		)
		(pad "167" smd rect
			(at -4.59994 18.699988 270)
			(size 1.8034 0.508)
			(layers "B.Cu" "B.Mask" "B.Paste")
			(net "GND")
		)
		(pad "168" smd rect
			(at -4.59994 19.550126 270)
			(size 1.8034 0.508)
			(layers "B.Cu" "B.Mask" "B.Paste")
			(net "M_F_DQ<11>")
		)
		(pad "169" smd rect
			(at -4.59994 20.40001 270)
			(size 1.8034 0.508)
			(layers "B.Cu" "B.Mask" "B.Paste")
			(net "GND")
		)
		(pad "170" smd rect
			(at -4.59994 21.249894 270)
			(size 1.8034 0.508)
			(layers "B.Cu" "B.Mask" "B.Paste")
			(net "M_F_DQ<21>")
		)
		(pad "171" smd rect
			(at -4.59994 22.100032 270)
			(size 1.8034 0.508)
			(layers "B.Cu" "B.Mask" "B.Paste")
			(net "GND")
		)
		(pad "172" smd rect
			(at -4.59994 22.949916 270)
			(size 1.8034 0.508)
			(layers "B.Cu" "B.Mask" "B.Paste")
			(net "M_F_DQ<17>")
		)
		(pad "173" smd rect
			(at -4.59994 23.800054 270)
			(size 1.8034 0.508)
			(layers "B.Cu" "B.Mask" "B.Paste")
			(net "GND")
		)
		(pad "174" smd rect
			(at -4.59994 24.649938 270)
			(size 1.8034 0.508)
			(layers "B.Cu" "B.Mask" "B.Paste")
			(net "M_F_DQS_DN<2>")
		)
		(pad "175" smd rect
			(at -4.59994 25.500076 270)
			(size 1.8034 0.508)
			(layers "B.Cu" "B.Mask" "B.Paste")
			(net "M_F_DQS_DP<2>")
		)
		(pad "176" smd rect
			(at -4.59994 26.34996 270)
			(size 1.8034 0.508)
			(layers "B.Cu" "B.Mask" "B.Paste")
			(net "GND")
		)
		(pad "177" smd rect
			(at -4.59994 27.200098 270)
			(size 1.8034 0.508)
			(layers "B.Cu" "B.Mask" "B.Paste")
			(net "M_F_DQ<23>")
		)
		(pad "178" smd rect
			(at -4.59994 28.049982 270)
			(size 1.8034 0.508)
			(layers "B.Cu" "B.Mask" "B.Paste")
			(net "GND")
		)
		(pad "179" smd rect
			(at -4.59994 28.90012 270)
			(size 1.8034 0.508)
			(layers "B.Cu" "B.Mask" "B.Paste")
			(net "M_F_DQ<19>")
		)
		(pad "180" smd rect
			(at -4.59994 29.750004 270)
			(size 1.8034 0.508)
			(layers "B.Cu" "B.Mask" "B.Paste")
			(net "GND")
		)
		(pad "181" smd rect
			(at -4.59994 30.599888 270)
			(size 1.8034 0.508)
			(layers "B.Cu" "B.Mask" "B.Paste")
			(net "M_F_DQ<29>")
		)
		(pad "182" smd rect
			(at -4.59994 31.450026 270)
			(size 1.8034 0.508)
			(layers "B.Cu" "B.Mask" "B.Paste")
			(net "GND")
		)
		(pad "183" smd rect
			(at -4.59994 32.29991 270)
			(size 1.8034 0.508)
			(layers "B.Cu" "B.Mask" "B.Paste")
			(net "M_F_DQ<25>")
		)
		(pad "184" smd rect
			(at -4.59994 33.150048 270)
			(size 1.8034 0.508)
			(layers "B.Cu" "B.Mask" "B.Paste")
			(net "GND")
		)
		(pad "185" smd rect
			(at -4.59994 33.999932 270)
			(size 1.8034 0.508)
			(layers "B.Cu" "B.Mask" "B.Paste")
			(net "M_F_DQS_DN<3>")
		)
		(pad "186" smd rect
			(at -4.59994 34.85007 270)
			(size 1.8034 0.508)
			(layers "B.Cu" "B.Mask" "B.Paste")
			(net "M_F_DQS_DP<3>")
		)
		(pad "187" smd rect
			(at -4.59994 35.699954 270)
			(size 1.8034 0.508)
			(layers "B.Cu" "B.Mask" "B.Paste")
			(net "GND")
		)
		(pad "188" smd rect
			(at -4.59994 36.550092 270)
			(size 1.8034 0.508)
			(layers "B.Cu" "B.Mask" "B.Paste")
			(net "M_F_DQ<31>")
		)
		(pad "189" smd rect
			(at -4.59994 37.399976 270)
			(size 1.8034 0.508)
			(layers "B.Cu" "B.Mask" "B.Paste")
			(net "GND")
		)
		(pad "190" smd rect
			(at -4.59994 38.250114 270)
			(size 1.8034 0.508)
			(layers "B.Cu" "B.Mask" "B.Paste")
			(net "M_F_DQ<27>")
		)
		(pad "191" smd rect
			(at -4.59994 39.099998 270)
			(size 1.8034 0.508)
			(layers "B.Cu" "B.Mask" "B.Paste")
			(net "GND")
		)
		(pad "192" smd rect
			(at -4.59994 39.949882 270)
			(size 1.8034 0.508)
			(layers "B.Cu" "B.Mask" "B.Paste")
			(net "M_F_ECC<5>")
		)
		(pad "193" smd rect
			(at -4.59994 40.80002 270)
			(size 1.8034 0.508)
			(layers "B.Cu" "B.Mask" "B.Paste")
			(net "GND")
		)
		(pad "194" smd rect
			(at -4.59994 41.649904 270)
			(size 1.8034 0.508)
			(layers "B.Cu" "B.Mask" "B.Paste")
			(net "M_F_ECC<1>")
		)
		(pad "195" smd rect
			(at -4.59994 42.500042 270)
			(size 1.8034 0.508)
			(layers "B.Cu" "B.Mask" "B.Paste")
			(net "GND")
		)
		(pad "196" smd rect
			(at -4.59994 43.349926 270)
			(size 1.8034 0.508)
			(layers "B.Cu" "B.Mask" "B.Paste")
			(net "M_F_DQS_DN<8>")
		)
		(pad "197" smd rect
			(at -4.59994 44.200064 270)
			(size 1.8034 0.508)
			(layers "B.Cu" "B.Mask" "B.Paste")
			(net "M_F_DQS_DP<8>")
		)
		(pad "198" smd rect
			(at -4.59994 45.049948 270)
			(size 1.8034 0.508)
			(layers "B.Cu" "B.Mask" "B.Paste")
			(net "GND")
		)
	)
)
